FILE_TYPE = CONNECTIVITY;
{Allegro Design Entry HDL 17.4-2019 S026 (4007227) 1/17/2022}
"PAGE_NUMBER" = 329;
0"NC";
1"CLK_100M_CPU1_CLK01_DP";
2"USB2_HUB_BUF_SWB_DP";
3"P5E_CPU1_P1_TX_BUF_C_DN<0>";
4"P5E_CPU1_P1_TX_BUF_C_DP<0>";
5"CLK_100M_CPU1_CLK01_DN";
6"USB2_HUB_BUF_SWB_DN";
7"P5E_CPU1_P0_TX_BUF_C_DP<0>";
8"P5E_CPU1_P0_TX_BUF_C_DN<0>";
9"P5E_CPU1_P1_RX_BUF_DP<0>";
10"P5E_CPU1_P1_RX_BUF_DN<0>";
11"P5E_CPU1_P0_RX_BUF_DP<0>";
12"RST_PERST_2_SWB_BUF_N";
13"GPU_FPGA_READY";
14"P5E_CPU1_P1_TX_BUF_C_DP<1>";
15"NC_J112_N2";
16"NC_J112_O2";
17"CLK_100M_GPU_FPGA_DN";
18"CLK_100M_GPU_FPGA_DP";
19"P5E_CPU1_P1_TX_BUF_C_DN<1>";
20"P5E_CPU1_P0_TX_BUF_C_DP<1>";
21"P5E_CPU1_P0_TX_BUF_C_DN<1>";
22"P5E_CPU1_P1_RX_BUF_DP<1>";
23"P5E_CPU1_P0_RX_BUF_DP<1>";
24"P5E_CPU1_P0_RX_BUF_DN<1>";
25"SMB_2_BMC_GPU_BUF_SDA";
26"SMB_2_BMC_GPU_BUF_SCL";
27"CLK_100M_CPU1_CLK11_DP";
28"P5E_CPU1_P1_TX_BUF_C_DN<2>";
29"CLK_100M_CPU1_CLK11_DN";
30"P5E_CPU1_P1_TX_BUF_C_DP<2>";
31"P5E_CPU1_P0_TX_BUF_C_DP<2>";
32"P5E_CPU1_P0_TX_BUF_C_DN<2>";
33"P5E_CPU1_P1_RX_BUF_DP<2>";
34"P5E_CPU1_P1_RX_BUF_DN<2>";
35"P5E_CPU1_P0_RX_BUF_DP<2>";
36"HGX_DETECT_N_ISO";
37"GPU_NVS_PWR_BRAKE_N_BUF";
38"SMB_1_BMC_GPU_BUF_SDA";
39"P5E_CPU1_P0_TX_BUF_C_DN<3>";
40"P5E_CPU1_P1_TX_BUF_C_DP<3>";
41"CLK_100M_CPU0_CLK11_DN";
42"CLK_100M_CPU0_CLK11_DP";
43"SMB_1_BMC_GPU_BUF_SCL";
44"GND\g";
45"P5E_CPU1_P1_TX_BUF_C_DN<3>";
46"P5E_CPU1_P0_TX_BUF_C_DP<3>";
47"P5E_CPU1_P0_RX_BUF_DN<2>";
48"GND\g";
49"P5E_CPU1_P0_RX_BUF_DN<4>";
50"P5E_CPU1_P0_RX_BUF_DP<4>";
51"P5E_CPU1_P1_RX_BUF_DN<4>";
52"P5E_CPU1_P1_RX_BUF_DP<4>";
53"P5E_CPU1_P0_TX_BUF_C_DN<4>";
54"P5E_CPU1_P0_TX_BUF_C_DP<4>";
55"RST_PERST_1_SWB_BUF_N";
56"GPU_FPGA_THERM_OVERT_N";
57"P2E_MB_BMC_TX_BUF_C_DN<0>";
58"P2E_MB_BMC_TX_BUF_C_DP<0>";
59"P2E_MB_BMC_RX_DN<0>";
60"P2E_MB_BMC_RX_DP<0>";
61"P5E_CPU1_P1_TX_BUF_C_DP<5>";
62"P5E_CPU1_P1_TX_BUF_C_DN<5>";
63"P5E_CPU1_P0_TX_BUF_C_DP<5>";
64"P5E_CPU1_P0_TX_BUF_C_DN<5>";
65"P5E_CPU1_P1_RX_BUF_DP<5>";
66"P5E_CPU1_P1_RX_BUF_DN<5>";
67"P5E_CPU1_P0_RX_BUF_DP<5>";
68"P5E_CPU1_P0_RX_BUF_DN<5>";
69"P3E_CPU1_P5_TX_C_DN<1>";
70"P3E_CPU1_P5_TX_C_DP<1>";
71"P3E_CPU1_P5_RX_DP<1>";
72"P3E_CPU1_P5_RX_DN<1>";
73"P5E_CPU1_P1_TX_BUF_C_DP<6>";
74"P5E_CPU1_P1_TX_BUF_C_DN<6>";
75"P5E_CPU1_P0_TX_BUF_C_DP<6>";
76"P5E_CPU1_P0_TX_BUF_C_DN<6>";
77"P5E_CPU1_P0_RX_BUF_DN<6>";
78"PRSNT_SWB_N";
79"RST_PERST_0_SWB_BUF_N";
80"P3E_CPU1_P5_TX_C_DP<0>";
81"P3E_CPU1_P5_TX_C_DN<0>";
82"P3E_CPU1_P5_RX_DP<0>";
83"P3E_CPU1_P5_RX_DN<0>";
84"P5E_CPU1_P1_TX_BUF_C_DP<7>";
85"P5E_CPU1_P0_TX_BUF_C_DP<7>";
86"P5E_CPU1_P1_TX_BUF_C_DN<7>";
87"NC_J112_O5";
88"NC_J112_P5";
89"NC_J112_R5";
90"NC_J112_S5";
91"P5E_CPU1_P1_TX_BUF_C_DP<4>";
92"P5E_CPU1_P1_TX_BUF_C_DN<4>";
93"P5E_CPU1_P1_RX_BUF_DP<6>";
94"P5E_CPU1_P1_RX_BUF_DN<6>";
95"P5E_CPU1_P1_RX_BUF_DP<7>";
96"P5E_CPU1_P1_RX_BUF_DN<7>";
97"P5E_CPU1_P0_TX_BUF_C_DN<7>";
98"P5E_CPU1_P0_RX_BUF_DP<6>";
99"P5E_CPU1_P0_RX_BUF_DP<7>";
100"P5E_CPU1_P0_RX_BUF_DN<7>";
101"P5E_CPU1_P1_RX_BUF_DN<1>";
102"P5E_CPU1_P0_RX_BUF_DP<3>";
103"P5E_CPU1_P0_RX_BUF_DN<3>";
104"P5E_CPU1_P1_RX_BUF_DN<3>";
105"P5E_CPU1_P1_RX_BUF_DP<3>";
106"P5E_CPU1_P0_RX_BUF_DN<0>";
%"CONN160_10131762101LF"
"2","(5075,1700)","0","pure_quanta","I102";
;
LOCATION"J112"
$SEC"2"
CDS_SEC"2"
MATERIAL"IO"
PART_TYPE"THLF"
CDS_LIB"pure_quanta"
CDS_LMAN_SYM_OUTLINE"-1075,2225,1075,-2225"
NEEDS_NO_SIZE"TRUE"
VALUE"CONN160_10131762-101LF"
PART_NUMBER"DFHSG0FR007";
"T4"
$PN"T4"37;
"S4"
$PN"S4"44;
"R4"
$PN"R4"38;
"Q4"
$PN"Q4"43;
"P4"
$PN"P4"44;
"O4"
$PN"O4"42;
"T3"
$PN"T3"44;
"S3"
$PN"S3"25;
"R3"
$PN"R3"26;
"Q3"
$PN"Q3"44;
"P3"
$PN"P3"27;
"O3"
$PN"O3"29;
"T2"
$PN"T2"13;
"S2"
$PN"S2"44;
"R2"
$PN"R2"18;
"Q2"
$PN"Q2"17;
"P2"
$PN"P2"44;
"O2"
$PN"O2"16;
"T1"
$PN"T1"44;
"S1"
$PN"S1"2;
"R1"
$PN"R1"6;
"Q1"
$PN"Q1"44;
"P1"
$PN"P1"1;
"O1"
$PN"O1"5;
"N4"
$PN"N4"41;
"M4"
$PN"M4"44;
"N3"
$PN"N3"44;
"M3"
$PN"M3"30;
"N2"
$PN"N2"15;
"M2"
$PN"M2"44;
"N1"
$PN"N1"44;
"M1"
$PN"M1"4;
"L1"
$PN"L1"3;
"L2"
$PN"L2"14;
"L3"
$PN"L3"28;
"L4"
$PN"L4"40;
"K1"
$PN"K1"44;
"K2"
$PN"K2"19;
"K3"
$PN"K3"44;
"K4"
$PN"K4"45;
"J1"
$PN"J1"7;
"J2"
$PN"J2"44;
"J3"
$PN"J3"31;
"J4"
$PN"J4"44;
"I1"
$PN"I1"8;
"I2"
$PN"I2"20;
"I3"
$PN"I3"32;
"I4"
$PN"I4"46;
"H1"
$PN"H1"44;
"H2"
$PN"H2"21;
"H3"
$PN"H3"44;
"H4"
$PN"H4"39;
"G1"
$PN"G1"9;
"G2"
$PN"G2"44;
"G3"
$PN"G3"33;
"G4"
$PN"G4"44;
"F1"
$PN"F1"10;
"F2"
$PN"F2"22;
"F3"
$PN"F3"34;
"F4"
$PN"F4"105;
"E1"
$PN"E1"44;
"E2"
$PN"E2"101;
"E3"
$PN"E3"44;
"E4"
$PN"E4"104;
"D1"
$PN"D1"11;
"D2"
$PN"D2"44;
"D3"
$PN"D3"35;
"D4"
$PN"D4"44;
"C1"
$PN"C1"106;
"C2"
$PN"C2"23;
"C3"
$PN"C3"47;
"C4"
$PN"C4"102;
"B1"
$PN"B1"44;
"B2"
$PN"B2"24;
"B3"
$PN"B3"44;
"B4"
$PN"B4"103;
"A1"
$PN"A1"12;
"A2"
$PN"A2"44;
"A3"
$PN"A3"36;
"A4"
$PN"A4"44;
%"UNIVERSAL_GND"
"1","(3700,-850)","0","pure_quanta_power","I59";
;
CDS_LIB"pure_quanta_power"
HDL_POWER"GND";
"A"44;
%"UNIVERSAL_GND"
"1","(-850,-975)","0","pure_quanta_power","I6";
;
CDS_LIB"pure_quanta_power"
HDL_POWER"GND";
"A"48;
%"CONN160_10131762101LF"
"1","(525,1625)","0","pure_quanta","I7";
;
LOCATION"J112"
$SEC"1"
CDS_SEC"1"
PART_TYPE"THLF"
MATERIAL"IO"
CDS_LIB"pure_quanta"
CDS_LMAN_SYM_OUTLINE"-1075,2225,1075,-2225"
NEEDS_NO_SIZE"TRUE"
VALUE"CONN160_10131762-101LF"
PART_NUMBER"DFHSG0FR007";
"T8"
$PN"T8"79;
"S8"
$PN"S8"48;
"R8"
$PN"R8"80;
"Q8"
$PN"Q8"81;
"P8"
$PN"P8"48;
"O8"
$PN"O8"82;
"T7"
$PN"T7"48;
"S7"
$PN"S7"69;
"R7"
$PN"R7"70;
"Q7"
$PN"Q7"48;
"P7"
$PN"P7"71;
"O7"
$PN"O7"72;
"T6"
$PN"T6"56;
"S6"
$PN"S6"48;
"R6"
$PN"R6"57;
"Q6"
$PN"Q6"58;
"P6"
$PN"P6"48;
"O6"
$PN"O6"59;
"T5"
$PN"T5"48;
"S5"
$PN"S5"90;
"R5"
$PN"R5"89;
"Q5"
$PN"Q5"48;
"P5"
$PN"P5"88;
"O5"
$PN"O5"87;
"N8"
$PN"N8"83;
"M8"
$PN"M8"48;
"N7"
$PN"N7"48;
"M7"
$PN"M7"73;
"N6"
$PN"N6"60;
"M6"
$PN"M6"48;
"N5"
$PN"N5"48;
"M5"
$PN"M5"91;
"L5"
$PN"L5"92;
"L6"
$PN"L6"61;
"L7"
$PN"L7"74;
"L8"
$PN"L8"84;
"K5"
$PN"K5"48;
"K6"
$PN"K6"62;
"K7"
$PN"K7"48;
"K8"
$PN"K8"86;
"J5"
$PN"J5"54;
"J6"
$PN"J6"48;
"J7"
$PN"J7"75;
"J8"
$PN"J8"48;
"I5"
$PN"I5"53;
"I6"
$PN"I6"63;
"I7"
$PN"I7"76;
"I8"
$PN"I8"85;
"H5"
$PN"H5"48;
"H6"
$PN"H6"64;
"H7"
$PN"H7"48;
"H8"
$PN"H8"97;
"G5"
$PN"G5"52;
"G6"
$PN"G6"48;
"G7"
$PN"G7"93;
"G8"
$PN"G8"48;
"F5"
$PN"F5"51;
"F6"
$PN"F6"65;
"F7"
$PN"F7"94;
"F8"
$PN"F8"95;
"E5"
$PN"E5"48;
"E6"
$PN"E6"66;
"E7"
$PN"E7"48;
"E8"
$PN"E8"96;
"D5"
$PN"D5"50;
"D6"
$PN"D6"48;
"D7"
$PN"D7"98;
"D8"
$PN"D8"48;
"C5"
$PN"C5"49;
"C6"
$PN"C6"67;
"C7"
$PN"C7"77;
"C8"
$PN"C8"99;
"B5"
$PN"B5"48;
"B6"
$PN"B6"68;
"B7"
$PN"B7"48;
"B8"
$PN"B8"100;
"A5"
$PN"A5"55;
"A6"
$PN"A6"48;
"A7"
$PN"A7"78;
"A8"
$PN"A8"48;
END.
